(kicad_pcb
	(version 20260206)
	(generator "pcbnew")
	(generator_version "10.0")
	(general
		(thickness 1.6)
		(legacy_teardrops no)
	)
	(paper "A4")
	(title_block
		(title "peb — Lightning_PEB_BRD.brd")
		(comment 1 "Lightning (Wiwynn / Facebook NVMe JBOF) / footprints 1168-1174 of 2563")
	)
	(layers
		(0 "F.Cu" signal "TOP")
		(4 "In1.Cu" signal "L2GND")
		(6 "In2.Cu" signal "L3")
		(8 "In3.Cu" signal "L4VCC")
		(10 "In4.Cu" signal "L5VCC")
		(12 "In5.Cu" signal "L6")
		(14 "In6.Cu" signal "L7GND")
		(2 "B.Cu" signal "BOTTOM")
		(9 "F.Adhes" user "F.Adhesive")
		(11 "B.Adhes" user "B.Adhesive")
		(13 "F.Paste" user "Package Geometry/Pastemask Top")
		(15 "B.Paste" user "Package Geometry/Pastemask Bottom")
		(5 "F.SilkS" user "Ref Des/Silkscreen Top")
		(7 "B.SilkS" user "Ref Des/Silkscreen Bottom")
		(1 "F.Mask" user "Board Geometry/Soldermask Top")
		(3 "B.Mask" user "Board Geometry/Soldermask Bottom")
		(17 "Dwgs.User" user "User.Drawings")
		(19 "Cmts.User" user "User.Comments")
		(21 "Eco1.User" user "User.Eco1")
		(23 "Eco2.User" user "User.Eco2")
		(25 "Edge.Cuts" user "Board Geometry/Outline")
		(27 "Margin" user)
		(31 "F.CrtYd" user "Package Geometry/Place Bound Top")
		(29 "B.CrtYd" user "Package Geometry/Place Bound Bottom")
		(35 "F.Fab" user "Ref Des/Assembly Top")
		(33 "B.Fab" user "Ref Des/Assembly Bottom")
	)
	(footprint ""
		(layer "F.Cu")
		(at 310.007 -63.2206)
		(property "Reference" "PG50"
			(at 0 0 0)
			(layer "F.SilkS")
			(hide yes)
			(effects
				(font
					(size 1.27 1.27)
				)
			)
		)
		(property "Value" "GAP-CLOSE-PWR-3-GP"
			(at 0.0254 -6.5786 0)
			(unlocked yes)
			(layer "F.Fab")
			(hide yes)
			(effects
				(font
					(size 1.016 1.016)
					(thickness 0.1524)
				)
			)
		)
		(property "Device Type" "GAP-CLOSE-PWR-3"
			(at 0.0254 -8.255 0)
			(unlocked yes)
			(layer "F.Fab")
			(hide yes)
			(effects
				(font
					(size 1.016 1.016)
					(thickness 0.1524)
				)
			)
		)
		(duplicate_pad_numbers_are_jumpers no)
		(fp_rect
			(start -0.7112 0.4572)
			(end 0.7112 -0.4572)
			(stroke
				(width 0)
				(type default)
			)
			(fill no)
			(layer "F.CrtYd")
		)
		(fp_poly
			(pts
				(xy -0.7112 -0.4572) (xy 0.7112 -0.4572) (xy 0.7112 0.4572) (xy -0.7112 0.4572)
			)
			(stroke
				(width 0)
				(type default)
			)
			(fill no)
			(layer "F.Fab")
		)
		(pad "1" smd rect
			(at -0.3048 0)
			(size 0.6604 0.762)
			(layers "F.Cu" "F.Mask" "F.Paste")
			(net "DUT_VDD")
		)
		(pad "2" smd rect
			(at 0.3048 0)
			(size 0.6604 0.762)
			(layers "F.Cu" "F.Mask" "F.Paste")
			(net "P0V9_E")
		)
	)
	(footprint ""
		(layer "F.Cu")
		(at 12.1158 -175.3362 90)
		(property "Reference" "Q96"
			(at 0 0 90)
			(layer "F.SilkS")
			(hide yes)
			(effects
				(font
					(size 1.27 1.27)
				)
			)
		)
		(property "Value" "2N7002K-1-GP"
			(at 0.127 -8.9662 90)
			(unlocked yes)
			(layer "F.Fab")
			(hide yes)
			(effects
				(font
					(size 1.016 1.016)
					(thickness 0.1524)
				)
			)
		)
		(property "Device Type" "SOT23DGS2D4H44"
			(at 0.127 -10.4902 90)
			(unlocked yes)
			(layer "F.Fab")
			(hide yes)
			(effects
				(font
					(size 1.016 1.016)
					(thickness 0.1524)
				)
			)
		)
		(duplicate_pad_numbers_are_jumpers no)
		(fp_line
			(start 1.651 -1.778)
			(end -1.651 -1.778)
			(stroke
				(width 0.1524)
				(type default)
			)
			(layer "F.SilkS")
		)
		(fp_line
			(start -1.651 -1.778)
			(end -1.651 1.778)
			(stroke
				(width 0.1524)
				(type default)
			)
			(layer "F.SilkS")
		)
		(fp_line
			(start 1.651 1.778)
			(end 1.651 -1.778)
			(stroke
				(width 0.1524)
				(type default)
			)
			(layer "F.SilkS")
		)
		(fp_line
			(start -1.651 1.778)
			(end 1.651 1.778)
			(stroke
				(width 0.1524)
				(type default)
			)
			(layer "F.SilkS")
		)
		(fp_poly
			(pts
				(xy -1.778 1.8796) (xy -1.778 -1.8796) (xy 1.778 -1.8796) (xy 1.778 1.8796)
			)
			(stroke
				(width 0)
				(type default)
			)
			(fill no)
			(layer "F.CrtYd")
		)
		(fp_poly
			(pts
				(xy -1.778 1.8796) (xy -1.778 -1.8796) (xy 1.778 -1.8796) (xy 1.778 1.8796)
			)
			(stroke
				(width 0)
				(type default)
			)
			(fill no)
			(layer "F.Fab")
		)
		(pad "D" smd custom
			(at 0 -0.9525 90)
			(size 0.1905 0.1905)
			(layers "F.Cu" "F.Mask" "F.Paste")
			(net "Q95_G")
			(options
				(clearance outline)
				(anchor circle)
			)
			(primitives
				(gr_poly
					(pts
						(arc
							(start -0.1778 0.5715)
							(mid -0.321484 0.511984)
							(end -0.381 0.3683)
						)
						(arc
							(start -0.381 -0.3683)
							(mid -0.321484 -0.511984)
							(end -0.1778 -0.5715)
						)
						(arc
							(start 0.1778 -0.5715)
							(mid 0.321484 -0.511984)
							(end 0.381 -0.3683)
						)
						(arc
							(start 0.381 0.3683)
							(mid 0.321484 0.511984)
							(end 0.1778 0.5715)
						)
					)
					(width 0)
					(fill yes)
				)
			)
		)
		(pad "G" smd custom
			(at -0.98425 0.9525 90)
			(size 0.1905 0.1905)
			(layers "F.Cu" "F.Mask" "F.Paste")
			(net "TRAY_MBP_CTRL_EN_N")
			(options
				(clearance outline)
				(anchor circle)
			)
			(primitives
				(gr_poly
					(pts
						(arc
							(start -0.1778 0.5715)
							(mid -0.321484 0.511984)
							(end -0.381 0.3683)
						)
						(arc
							(start -0.381 -0.3683)
							(mid -0.321484 -0.511984)
							(end -0.1778 -0.5715)
						)
						(arc
							(start 0.1778 -0.5715)
							(mid 0.321484 -0.511984)
							(end 0.381 -0.3683)
						)
						(arc
							(start 0.381 0.3683)
							(mid 0.321484 0.511984)
							(end 0.1778 0.5715)
						)
					)
					(width 0)
					(fill yes)
				)
			)
		)
		(pad "S" smd custom
			(at 0.98425 0.9525 90)
			(size 0.1905 0.1905)
			(layers "F.Cu" "F.Mask" "F.Paste")
			(net "GND")
			(options
				(clearance outline)
				(anchor circle)
			)
			(primitives
				(gr_poly
					(pts
						(arc
							(start -0.1778 0.5715)
							(mid -0.321484 0.511984)
							(end -0.381 0.3683)
						)
						(arc
							(start -0.381 -0.3683)
							(mid -0.321484 -0.511984)
							(end -0.1778 -0.5715)
						)
						(arc
							(start 0.1778 -0.5715)
							(mid 0.321484 -0.511984)
							(end 0.381 -0.3683)
						)
						(arc
							(start 0.381 0.3683)
							(mid 0.321484 0.511984)
							(end 0.1778 0.5715)
						)
					)
					(width 0)
					(fill yes)
				)
			)
		)
	)
	(footprint ""
		(layer "F.Cu")
		(at 47.244 -196.596 180)
		(property "Reference" "R887"
			(at 0 0 180)
			(layer "F.SilkS")
			(hide yes)
			(effects
				(font
					(size 1.27 1.27)
				)
			)
		)
		(property "Value" "10KR2F-2-GP"
			(at 0.064008 -3.993896 180)
			(unlocked yes)
			(layer "F.Fab")
			(hide yes)
			(effects
				(font
					(size 1.016 1.016)
					(thickness 0.1524)
				)
			)
		)
		(property "Device Type" "R402H16"
			(at 0.064008 -5.517896 180)
			(unlocked yes)
			(layer "F.Fab")
			(hide yes)
			(effects
				(font
					(size 1.016 1.016)
					(thickness 0.1524)
				)
			)
		)
		(duplicate_pad_numbers_are_jumpers no)
		(fp_line
			(start 0.508 -0.9398)
			(end -0.508 -0.9398)
			(stroke
				(width 0.1524)
				(type default)
			)
			(layer "F.SilkS")
		)
		(fp_line
			(start -0.508 -0.9398)
			(end -0.508 0.9398)
			(stroke
				(width 0.1524)
				(type default)
			)
			(layer "F.SilkS")
		)
		(fp_rect
			(start -0.508 0.9398)
			(end 0.508 -0.9398)
			(stroke
				(width 0)
				(type default)
			)
			(fill no)
			(layer "F.CrtYd")
		)
		(fp_rect
			(start -0.508 0.9398)
			(end 0.508 -0.9398)
			(stroke
				(width 0)
				(type default)
			)
			(fill no)
			(layer "F.Fab")
		)
		(pad "1" smd custom
			(at 0 -0.4445 180)
			(size 0.1397 0.1397)
			(layers "F.Cu" "F.Mask" "F.Paste")
			(net "I2C7_BUF_READY")
			(options
				(clearance outline)
				(anchor circle)
			)
			(primitives
				(gr_poly
					(pts
						(arc
							(start -0.1778 -0.2794)
							(mid -0.249642 -0.249642)
							(end -0.2794 -0.1778)
						)
						(arc
							(start -0.2794 0.1778)
							(mid -0.249642 0.249642)
							(end -0.1778 0.2794)
						)
						(arc
							(start 0.1778 0.2794)
							(mid 0.249642 0.249642)
							(end 0.2794 0.1778)
						)
						(arc
							(start 0.2794 -0.1778)
							(mid 0.249642 -0.249642)
							(end 0.1778 -0.2794)
						)
					)
					(width 0)
					(fill yes)
				)
			)
		)
		(pad "2" smd custom
			(at 0 0.4445 180)
			(size 0.1397 0.1397)
			(layers "F.Cu" "F.Mask" "F.Paste")
			(net "P3V3_STBY")
			(options
				(clearance outline)
				(anchor circle)
			)
			(primitives
				(gr_poly
					(pts
						(arc
							(start -0.1778 -0.2794)
							(mid -0.249642 -0.249642)
							(end -0.2794 -0.1778)
						)
						(arc
							(start -0.2794 0.1778)
							(mid -0.249642 0.249642)
							(end -0.1778 0.2794)
						)
						(arc
							(start 0.1778 0.2794)
							(mid 0.249642 0.249642)
							(end 0.2794 0.1778)
						)
						(arc
							(start 0.2794 -0.1778)
							(mid 0.249642 -0.249642)
							(end 0.1778 -0.2794)
						)
					)
					(width 0)
					(fill yes)
				)
			)
		)
	)
	(footprint ""
		(layer "F.Cu")
		(at 62.2046 -109.8804)
		(property "Reference" "R313"
			(at 0 0 0)
			(layer "F.SilkS")
			(hide yes)
			(effects
				(font
					(size 1.27 1.27)
				)
			)
		)
		(property "Value" "4K7R2F-GP"
			(at 0.064008 -3.993896 0)
			(unlocked yes)
			(layer "F.Fab")
			(hide yes)
			(effects
				(font
					(size 1.016 1.016)
					(thickness 0.1524)
				)
			)
		)
		(property "Device Type" "R402H16"
			(at 0.064008 -5.517896 0)
			(unlocked yes)
			(layer "F.Fab")
			(hide yes)
			(effects
				(font
					(size 1.016 1.016)
					(thickness 0.1524)
				)
			)
		)
		(duplicate_pad_numbers_are_jumpers no)
		(fp_line
			(start -0.508 -0.9398)
			(end -0.508 0.9398)
			(stroke
				(width 0.1524)
				(type default)
			)
			(layer "F.SilkS")
		)
		(fp_line
			(start 0.508 -0.9398)
			(end -0.508 -0.9398)
			(stroke
				(width 0.1524)
				(type default)
			)
			(layer "F.SilkS")
		)
		(fp_rect
			(start -0.508 0.9398)
			(end 0.508 -0.9398)
			(stroke
				(width 0)
				(type default)
			)
			(fill no)
			(layer "F.CrtYd")
		)
		(fp_rect
			(start -0.508 0.9398)
			(end 0.508 -0.9398)
			(stroke
				(width 0)
				(type default)
			)
			(fill no)
			(layer "F.Fab")
		)
		(pad "1" smd custom
			(at 0 -0.4445)
			(size 0.1397 0.1397)
			(layers "F.Cu" "F.Mask" "F.Paste")
			(net "P3V3_STBY")
			(options
				(clearance outline)
				(anchor circle)
			)
			(primitives
				(gr_poly
					(pts
						(arc
							(start -0.1778 -0.2794)
							(mid -0.249642 -0.249642)
							(end -0.2794 -0.1778)
						)
						(arc
							(start -0.2794 0.1778)
							(mid -0.249642 0.249642)
							(end -0.1778 0.2794)
						)
						(arc
							(start 0.1778 0.2794)
							(mid 0.249642 0.249642)
							(end 0.2794 0.1778)
						)
						(arc
							(start 0.2794 -0.1778)
							(mid 0.249642 -0.249642)
							(end 0.1778 -0.2794)
						)
					)
					(width 0)
					(fill yes)
				)
			)
		)
		(pad "2" smd custom
			(at 0 0.4445)
			(size 0.1397 0.1397)
			(layers "F.Cu" "F.Mask" "F.Paste")
			(net "I2C5_LS_G1")
			(options
				(clearance outline)
				(anchor circle)
			)
			(primitives
				(gr_poly
					(pts
						(arc
							(start -0.1778 -0.2794)
							(mid -0.249642 -0.249642)
							(end -0.2794 -0.1778)
						)
						(arc
							(start -0.2794 0.1778)
							(mid -0.249642 0.249642)
							(end -0.1778 0.2794)
						)
						(arc
							(start 0.1778 0.2794)
							(mid 0.249642 0.249642)
							(end 0.2794 0.1778)
						)
						(arc
							(start 0.2794 -0.1778)
							(mid 0.249642 -0.249642)
							(end 0.1778 -0.2794)
						)
					)
					(width 0)
					(fill yes)
				)
			)
		)
	)
	(footprint ""
		(layer "F.Cu")
		(at 225.1964 -187.9092 90)
		(property "Reference" "C4124"
			(at 0 0 90)
			(layer "F.SilkS")
			(hide yes)
			(effects
				(font
					(size 1.27 1.27)
				)
			)
		)
		(property "Value" "SCD1U25V3KX-GP"
			(at 0 -2.8194 90)
			(unlocked yes)
			(layer "F.Fab")
			(hide yes)
			(effects
				(font
					(size 1.016 1.016)
					(thickness 0.1524)
				)
			)
		)
		(property "Device Type" "C603H36"
			(at 0 -4.3434 90)
			(unlocked yes)
			(layer "F.Fab")
			(hide yes)
			(effects
				(font
					(size 1.016 1.016)
					(thickness 0.1524)
				)
			)
		)
		(duplicate_pad_numbers_are_jumpers no)
		(fp_line
			(start 0.508 0)
			(end -0.508 0)
			(stroke
				(width 0.2032)
				(type default)
			)
			(layer "F.SilkS")
		)
		(fp_rect
			(start -0.5842 1.3335)
			(end 0.5842 -1.3335)
			(stroke
				(width 0)
				(type default)
			)
			(fill no)
			(layer "F.CrtYd")
		)
		(fp_rect
			(start -0.5842 1.3335)
			(end 0.5842 -1.3335)
			(stroke
				(width 0)
				(type default)
			)
			(fill no)
			(layer "F.Fab")
		)
		(pad "1" smd custom
			(at 0 -0.762 90)
			(size 0.2159 0.2159)
			(layers "F.Cu" "F.Mask" "F.Paste")
			(net "GND")
			(options
				(clearance outline)
				(anchor circle)
			)
			(primitives
				(gr_poly
					(pts
						(arc
							(start -0.3302 -0.4318)
							(mid -0.402042 -0.402042)
							(end -0.4318 -0.3302)
						)
						(arc
							(start -0.4318 0.3302)
							(mid -0.402042 0.402042)
							(end -0.3302 0.4318)
						)
						(arc
							(start 0.3302 0.4318)
							(mid 0.402042 0.402042)
							(end 0.4318 0.3302)
						)
						(arc
							(start 0.4318 -0.3302)
							(mid 0.402042 -0.402042)
							(end 0.3302 -0.4318)
						)
					)
					(width 0)
					(fill yes)
				)
			)
		)
		(pad "2" smd custom
			(at 0 0.762 90)
			(size 0.2159 0.2159)
			(layers "F.Cu" "F.Mask" "F.Paste")
			(net "SSD_PWREN8_R")
			(options
				(clearance outline)
				(anchor circle)
			)
			(primitives
				(gr_poly
					(pts
						(arc
							(start -0.3302 -0.4318)
							(mid -0.402042 -0.402042)
							(end -0.4318 -0.3302)
						)
						(arc
							(start -0.4318 0.3302)
							(mid -0.402042 0.402042)
							(end -0.3302 0.4318)
						)
						(arc
							(start 0.3302 0.4318)
							(mid 0.402042 0.402042)
							(end 0.4318 0.3302)
						)
						(arc
							(start 0.4318 -0.3302)
							(mid 0.402042 -0.402042)
							(end 0.3302 -0.4318)
						)
					)
					(width 0)
					(fill yes)
				)
			)
		)
	)
	(footprint ""
		(layer "F.Cu")
		(at 25.9842 -83.4644 90)
		(property "Reference" "R382"
			(at 0 0 90)
			(layer "F.SilkS")
			(hide yes)
			(effects
				(font
					(size 1.27 1.27)
				)
			)
		)
		(property "Value" "0R2J-2-GP"
			(at 0.064008 -3.993896 90)
			(unlocked yes)
			(layer "F.Fab")
			(hide yes)
			(effects
				(font
					(size 1.016 1.016)
					(thickness 0.1524)
				)
			)
		)
		(property "Device Type" "R402H16"
			(at 0.064008 -5.517896 90)
			(unlocked yes)
			(layer "F.Fab")
			(hide yes)
			(effects
				(font
					(size 1.016 1.016)
					(thickness 0.1524)
				)
			)
		)
		(duplicate_pad_numbers_are_jumpers no)
		(fp_line
			(start 0.508 -0.9398)
			(end -0.508 -0.9398)
			(stroke
				(width 0.1524)
				(type default)
			)
			(layer "F.SilkS")
		)
		(fp_line
			(start -0.508 -0.9398)
			(end -0.508 0.9398)
			(stroke
				(width 0.1524)
				(type default)
			)
			(layer "F.SilkS")
		)
		(fp_rect
			(start -0.508 0.9398)
			(end 0.508 -0.9398)
			(stroke
				(width 0)
				(type default)
			)
			(fill no)
			(layer "F.CrtYd")
		)
		(fp_rect
			(start -0.508 0.9398)
			(end 0.508 -0.9398)
			(stroke
				(width 0)
				(type default)
			)
			(fill no)
			(layer "F.Fab")
		)
		(pad "1" smd custom
			(at 0 -0.4445 90)
			(size 0.1397 0.1397)
			(layers "F.Cu" "F.Mask" "F.Paste")
			(net "NVM_CS_N")
			(options
				(clearance outline)
				(anchor circle)
			)
			(primitives
				(gr_poly
					(pts
						(arc
							(start -0.1778 -0.2794)
							(mid -0.249642 -0.249642)
							(end -0.2794 -0.1778)
						)
						(arc
							(start -0.2794 0.1778)
							(mid -0.249642 0.249642)
							(end -0.1778 0.2794)
						)
						(arc
							(start 0.1778 0.2794)
							(mid 0.249642 0.249642)
							(end 0.2794 0.1778)
						)
						(arc
							(start 0.2794 -0.1778)
							(mid 0.249642 -0.249642)
							(end 0.1778 -0.2794)
						)
					)
					(width 0)
					(fill yes)
				)
			)
		)
		(pad "2" smd custom
			(at 0 0.4445 90)
			(size 0.1397 0.1397)
			(layers "F.Cu" "F.Mask" "F.Paste")
			(net "I210_CS_N_R")
			(options
				(clearance outline)
				(anchor circle)
			)
			(primitives
				(gr_poly
					(pts
						(arc
							(start -0.1778 -0.2794)
							(mid -0.249642 -0.249642)
							(end -0.2794 -0.1778)
						)
						(arc
							(start -0.2794 0.1778)
							(mid -0.249642 0.249642)
							(end -0.1778 0.2794)
						)
						(arc
							(start 0.1778 0.2794)
							(mid 0.249642 0.249642)
							(end 0.2794 0.1778)
						)
						(arc
							(start 0.2794 -0.1778)
							(mid 0.249642 -0.249642)
							(end 0.1778 -0.2794)
						)
					)
					(width 0)
					(fill yes)
				)
			)
		)
	)
	(footprint ""
		(layer "F.Cu")
		(at 328.803 -86.487)
		(property "Reference" "R4172"
			(at 0 0 0)
			(layer "F.SilkS")
			(hide yes)
			(effects
				(font
					(size 1.27 1.27)
				)
			)
		)
		(property "Value" "4K7R2F-GP"
			(at 0.064008 -3.993896 0)
			(unlocked yes)
			(layer "F.Fab")
			(hide yes)
			(effects
				(font
					(size 1.016 1.016)
					(thickness 0.1524)
				)
			)
		)
		(property "Device Type" "R402H16"
			(at 0.064008 -5.517896 0)
			(unlocked yes)
			(layer "F.Fab")
			(hide yes)
			(effects
				(font
					(size 1.016 1.016)
					(thickness 0.1524)
				)
			)
		)
		(duplicate_pad_numbers_are_jumpers no)
		(fp_line
			(start -0.508 -0.9398)
			(end -0.508 0.9398)
			(stroke
				(width 0.1524)
				(type default)
			)
			(layer "F.SilkS")
		)
		(fp_line
			(start 0.508 -0.9398)
			(end -0.508 -0.9398)
			(stroke
				(width 0.1524)
				(type default)
			)
			(layer "F.SilkS")
		)
		(fp_rect
			(start -0.508 0.9398)
			(end 0.508 -0.9398)
			(stroke
				(width 0)
				(type default)
			)
			(fill no)
			(layer "F.CrtYd")
		)
		(fp_rect
			(start -0.508 0.9398)
			(end 0.508 -0.9398)
			(stroke
				(width 0)
				(type default)
			)
			(fill no)
			(layer "F.Fab")
		)
		(pad "1" smd custom
			(at 0 -0.4445)
			(size 0.1397 0.1397)
			(layers "F.Cu" "F.Mask" "F.Paste")
			(net "UPLINK6")
			(options
				(clearance outline)
				(anchor circle)
			)
			(primitives
				(gr_poly
					(pts
						(arc
							(start -0.1778 -0.2794)
							(mid -0.249642 -0.249642)
							(end -0.2794 -0.1778)
						)
						(arc
							(start -0.2794 0.1778)
							(mid -0.249642 0.249642)
							(end -0.1778 0.2794)
						)
						(arc
							(start 0.1778 0.2794)
							(mid 0.249642 0.249642)
							(end 0.2794 0.1778)
						)
						(arc
							(start 0.2794 -0.1778)
							(mid 0.249642 -0.249642)
							(end 0.1778 -0.2794)
						)
					)
					(width 0)
					(fill yes)
				)
			)
		)
		(pad "2" smd custom
			(at 0 0.4445)
			(size 0.1397 0.1397)
			(layers "F.Cu" "F.Mask" "F.Paste")
			(net "P3V3_STBY")
			(options
				(clearance outline)
				(anchor circle)
			)
			(primitives
				(gr_poly
					(pts
						(arc
							(start -0.1778 -0.2794)
							(mid -0.249642 -0.249642)
							(end -0.2794 -0.1778)
						)
						(arc
							(start -0.2794 0.1778)
							(mid -0.249642 0.249642)
							(end -0.1778 0.2794)
						)
						(arc
							(start 0.1778 0.2794)
							(mid 0.249642 0.249642)
							(end 0.2794 0.1778)
						)
						(arc
							(start 0.2794 -0.1778)
							(mid 0.249642 -0.249642)
							(end 0.1778 -0.2794)
						)
					)
					(width 0)
					(fill yes)
				)
			)
		)
	)
)
